# T6G (Grand Teton) — schematic netlist excerpt (pin names and nets, part order shuffled) for the footprints in the layout excerpt that follows; sources: Cadence DE-HDL packaged netlist, KiCad conversion of 04192023_DAF0TMB3IC0_F0TG_MB_C_brd_V02_OCP.brd

R1526  Q_RES  0 5% CHIP  pkg 0402LF  page 240 : A = PDB_PRSNT_N ; B = PDB_PRSNT_R_N
C6716  Q_CAP_DIFFBUS  DIFF BUS_0.22UF 6.3V 20% X6S  pkg C0201  page 341 : \1\ = P5E_CPU1_P2_TX_BUF_C_DN<11> ; \2\ = P5E_CPU1_P2_TX_BUF_DN<11>
R6029  Q_RES  33 5% CHIP  pkg 0402LF  page 80 : A = CLK_GEN2_BMC_RC_OE_N ; B = CLK_GEN2_BMC_RC_OE_R_N

(kicad_pcb
	(version 20260206)
	(generator "pcbnew")
	(generator_version "10.0")
	(general
		(thickness 1.6)
		(legacy_teardrops no)
	)
	(paper "A4")
	(title_block
		(title "04192023_DAF0TMB3IC0_F0TG_MB_C_brd_V02_OCP.brd")
		(comment 1 "Grand Teton / footprints 4631-4633 of 8354")
	)
	(layers
		(0 "F.Cu" signal "TOP")
		(4 "In1.Cu" signal "GND")
		(6 "In2.Cu" signal "IN1")
		(8 "In3.Cu" signal "GND1")
		(10 "In4.Cu" signal "IN2")
		(12 "In5.Cu" signal "GND2")
		(14 "In6.Cu" signal "IN3")
		(16 "In7.Cu" signal "GND3")
		(18 "In8.Cu" signal "VCC")
		(20 "In9.Cu" signal "VCC1")
		(22 "In10.Cu" signal "GND4")
		(24 "In11.Cu" signal "IN4")
		(26 "In12.Cu" signal "GND5")
		(28 "In13.Cu" signal "IN5")
		(30 "In14.Cu" signal "GND6")
		(32 "In15.Cu" signal "IN6")
		(34 "In16.Cu" signal "GND7")
		(2 "B.Cu" signal "BOTTOM")
		(9 "F.Adhes" user "F.Adhesive")
		(11 "B.Adhes" user "B.Adhesive")
		(13 "F.Paste" user "Package Geometry/Pastemask Top")
		(15 "B.Paste" user "Package Geometry/Pastemask Bottom")
		(5 "F.SilkS" user "Ref Des/Silkscreen Top")
		(7 "B.SilkS" user "Ref Des/Silkscreen Bottom")
		(1 "F.Mask" user "Board Geometry/Soldermask Top")
		(3 "B.Mask" user "Board Geometry/Soldermask Bottom")
		(17 "Dwgs.User" user "User.Drawings")
		(19 "Cmts.User" user "User.Comments")
		(21 "Eco1.User" user "User.Eco1")
		(23 "Eco2.User" user "User.Eco2")
		(25 "Edge.Cuts" user "Board Geometry/Outline")
		(27 "Margin" user)
		(31 "F.CrtYd" user "Package Geometry/Place Bound Top")
		(29 "B.CrtYd" user "Package Geometry/Place Bound Bottom")
		(35 "F.Fab" user "Ref Des/Assembly Top")
		(33 "B.Fab" user "Ref Des/Assembly Bottom")
	)
	(footprint ""
		(layer "F.Cu")
		(at 171.196 -121.376948)
		(property "Reference" "R6029"
			(at 0 0 0)
			(layer "F.SilkS")
			(hide yes)
			(effects
				(font
					(size 1.27 1.27)
				)
			)
		)
		(property "Value" ""
			(at 0 0 0)
			(layer "F.Fab")
			(effects
				(font
					(size 1.27 1.27)
				)
			)
		)
		(duplicate_pad_numbers_are_jumpers no)
		(fp_line
			(start -0.7874 -0.4064)
			(end 0.7874 -0.4064)
			(stroke
				(width 0.1524)
				(type default)
			)
			(layer "F.SilkS")
		)
		(fp_line
			(start -0.7874 0.4064)
			(end -0.7874 -0.4064)
			(stroke
				(width 0.1524)
				(type default)
			)
			(layer "F.SilkS")
		)
		(fp_line
			(start 0.7874 -0.4064)
			(end 0.7874 0.4064)
			(stroke
				(width 0.1524)
				(type default)
			)
			(layer "F.SilkS")
		)
		(fp_line
			(start 0.7874 0.4064)
			(end -0.7874 0.4064)
			(stroke
				(width 0.1524)
				(type default)
			)
			(layer "F.SilkS")
		)
		(fp_line
			(start -0.67945 -0.305054)
			(end -0.12065 -0.305054)
			(stroke
				(width 0.1)
				(type default)
			)
			(layer "F.Fab")
		)
		(fp_line
			(start -0.67945 0.3048)
			(end -0.67945 -0.305054)
			(stroke
				(width 0.1)
				(type default)
			)
			(layer "F.Fab")
		)
		(fp_line
			(start -0.12065 -0.305054)
			(end -0.12065 -0.2794)
			(stroke
				(width 0.1)
				(type default)
			)
			(layer "F.Fab")
		)
		(fp_line
			(start -0.12065 -0.2794)
			(end 0.12065 -0.2794)
			(stroke
				(width 0.1)
				(type default)
			)
			(layer "F.Fab")
		)
		(fp_line
			(start -0.12065 0.2794)
			(end -0.12065 0.3048)
			(stroke
				(width 0.1)
				(type default)
			)
			(layer "F.Fab")
		)
		(fp_line
			(start -0.12065 0.3048)
			(end -0.67945 0.3048)
			(stroke
				(width 0.1)
				(type default)
			)
			(layer "F.Fab")
		)
		(fp_line
			(start 0.120396 0.2794)
			(end -0.12065 0.2794)
			(stroke
				(width 0.1)
				(type default)
			)
			(layer "F.Fab")
		)
		(fp_line
			(start 0.120396 0.3048)
			(end 0.120396 0.2794)
			(stroke
				(width 0.1)
				(type default)
			)
			(layer "F.Fab")
		)
		(fp_line
			(start 0.12065 -0.3048)
			(end 0.67945 -0.3048)
			(stroke
				(width 0.1)
				(type default)
			)
			(layer "F.Fab")
		)
		(fp_line
			(start 0.12065 -0.2794)
			(end 0.12065 -0.3048)
			(stroke
				(width 0.1)
				(type default)
			)
			(layer "F.Fab")
		)
		(fp_line
			(start 0.67945 -0.3048)
			(end 0.67945 0.3048)
			(stroke
				(width 0.1)
				(type default)
			)
			(layer "F.Fab")
		)
		(fp_line
			(start 0.67945 0.3048)
			(end 0.120396 0.3048)
			(stroke
				(width 0.1)
				(type default)
			)
			(layer "F.Fab")
		)
		(pad "1" smd circle
			(at -0.40005 0)
			(size 0 0)
			(layers "F.Cu" "F.Mask" "F.Paste")
			(net "CLK_GEN2_BMC_RC_OE_N")
		)
		(pad "2" smd circle
			(at 0.40005 0)
			(size 0 0)
			(layers "F.Cu" "F.Mask" "F.Paste")
			(net "CLK_GEN2_BMC_RC_OE_R_N")
		)
	)
	(footprint ""
		(layer "F.Cu")
		(at 148.564346 -408.517344 -90)
		(property "Reference" "C6716"
			(at 0 0 270)
			(layer "F.SilkS")
			(hide yes)
			(effects
				(font
					(size 1.27 1.27)
				)
			)
		)
		(property "Value" ""
			(at 0 0 270)
			(layer "F.Fab")
			(effects
				(font
					(size 1.27 1.27)
				)
			)
		)
		(duplicate_pad_numbers_are_jumpers no)
		(fp_line
			(start -0.299974 0.150114)
			(end -0.299974 -0.150114)
			(stroke
				(width 0.1)
				(type default)
			)
			(layer "F.Fab")
		)
		(fp_line
			(start 0.299974 0.150114)
			(end -0.299974 0.150114)
			(stroke
				(width 0.1)
				(type default)
			)
			(layer "F.Fab")
		)
		(fp_line
			(start -0.299974 -0.150114)
			(end 0.299974 -0.150114)
			(stroke
				(width 0.1)
				(type default)
			)
			(layer "F.Fab")
		)
		(fp_line
			(start 0.299974 -0.150114)
			(end 0.299974 0.150114)
			(stroke
				(width 0.1)
				(type default)
			)
			(layer "F.Fab")
		)
		(pad "1" smd rect
			(at -0.2667 0 270)
			(size 0.3048 0.381)
			(layers "F.Cu" "F.Mask" "F.Paste")
			(net "P5E_CPU1_P2_TX_BUF_C_DN<11>")
		)
		(pad "2" smd rect
			(at 0.2667 0 270)
			(size 0.3048 0.381)
			(layers "F.Cu" "F.Mask" "F.Paste")
			(net "P5E_CPU1_P2_TX_BUF_DN<11>")
		)
	)
	(footprint ""
		(layer "F.Cu")
		(at 266.726416 -422.626536 -90)
		(property "Reference" "R1526"
			(at 0 0 270)
			(layer "F.SilkS")
			(hide yes)
			(effects
				(font
					(size 1.27 1.27)
				)
			)
		)
		(property "Value" ""
			(at 0 0 270)
			(layer "F.Fab")
			(effects
				(font
					(size 1.27 1.27)
				)
			)
		)
		(duplicate_pad_numbers_are_jumpers no)
		(fp_line
			(start -0.7874 0.4064)
			(end -0.7874 -0.4064)
			(stroke
				(width 0.1524)
				(type default)
			)
			(layer "F.SilkS")
		)
		(fp_line
			(start 0.7874 0.4064)
			(end -0.7874 0.4064)
			(stroke
				(width 0.1524)
				(type default)
			)
			(layer "F.SilkS")
		)
		(fp_line
			(start -0.7874 -0.4064)
			(end 0.7874 -0.4064)
			(stroke
				(width 0.1524)
				(type default)
			)
			(layer "F.SilkS")
		)
		(fp_line
			(start 0.7874 -0.4064)
			(end 0.7874 0.4064)
			(stroke
				(width 0.1524)
				(type default)
			)
			(layer "F.SilkS")
		)
		(fp_line
			(start -0.67945 0.3048)
			(end -0.67945 -0.305054)
			(stroke
				(width 0.1)
				(type default)
			)
			(layer "F.Fab")
		)
		(fp_line
			(start -0.12065 0.3048)
			(end -0.67945 0.3048)
			(stroke
				(width 0.1)
				(type default)
			)
			(layer "F.Fab")
		)
		(fp_line
			(start 0.120396 0.3048)
			(end 0.120396 0.2794)
			(stroke
				(width 0.1)
				(type default)
			)
			(layer "F.Fab")
		)
		(fp_line
			(start 0.67945 0.3048)
			(end 0.120396 0.3048)
			(stroke
				(width 0.1)
				(type default)
			)
			(layer "F.Fab")
		)
		(fp_line
			(start -0.12065 0.2794)
			(end -0.12065 0.3048)
			(stroke
				(width 0.1)
				(type default)
			)
			(layer "F.Fab")
		)
		(fp_line
			(start 0.120396 0.2794)
			(end -0.12065 0.2794)
			(stroke
				(width 0.1)
				(type default)
			)
			(layer "F.Fab")
		)
		(fp_line
			(start -0.12065 -0.2794)
			(end 0.12065 -0.2794)
			(stroke
				(width 0.1)
				(type default)
			)
			(layer "F.Fab")
		)
		(fp_line
			(start 0.12065 -0.2794)
			(end 0.12065 -0.3048)
			(stroke
				(width 0.1)
				(type default)
			)
			(layer "F.Fab")
		)
		(fp_line
			(start 0.12065 -0.3048)
			(end 0.67945 -0.3048)
			(stroke
				(width 0.1)
				(type default)
			)
			(layer "F.Fab")
		)
		(fp_line
			(start 0.67945 -0.3048)
			(end 0.67945 0.3048)
			(stroke
				(width 0.1)
				(type default)
			)
			(layer "F.Fab")
		)
		(fp_line
			(start -0.67945 -0.305054)
			(end -0.12065 -0.305054)
			(stroke
				(width 0.1)
				(type default)
			)
			(layer "F.Fab")
		)
		(fp_line
			(start -0.12065 -0.305054)
			(end -0.12065 -0.2794)
			(stroke
				(width 0.1)
				(type default)
			)
			(layer "F.Fab")
		)
		(pad "1" smd circle
			(at -0.40005 0 270)
			(size 0 0)
			(layers "F.Cu" "F.Mask" "F.Paste")
			(net "PDB_PRSNT_N")
		)
		(pad "2" smd circle
			(at 0.40005 0 270)
			(size 0 0)
			(layers "F.Cu" "F.Mask" "F.Paste")
			(net "PDB_PRSNT_R_N")
		)
	)
)
